(kicad_pcb
	(version 20260206)
	(generator "pcbnew")
	(generator_version "10.0")
	(general
		(thickness 1.6)
		(legacy_teardrops no)
	)
	(paper "A4")
	(title_block
		(title "12092022_DA0F0TFB6D0_F0T_FAN_BOARD_MP5048_D_brd_v02_OCP.brd")
		(comment 1 "Grand Teton / footprints 644-650 of 924")
	)
	(layers
		(0 "F.Cu" signal "TOP")
		(4 "In1.Cu" signal "GND")
		(6 "In2.Cu" signal "IN1")
		(8 "In3.Cu" signal "IN2")
		(10 "In4.Cu" signal "GND1")
		(2 "B.Cu" signal "BOTTOM")
		(9 "F.Adhes" user "F.Adhesive")
		(11 "B.Adhes" user "B.Adhesive")
		(13 "F.Paste" user "Package Geometry/Pastemask Top")
		(15 "B.Paste" user "Package Geometry/Pastemask Bottom")
		(5 "F.SilkS" user "Ref Des/Silkscreen Top")
		(7 "B.SilkS" user "Ref Des/Silkscreen Bottom")
		(1 "F.Mask" user "Board Geometry/Soldermask Top")
		(3 "B.Mask" user "Board Geometry/Soldermask Bottom")
		(17 "Dwgs.User" user "User.Drawings")
		(19 "Cmts.User" user "User.Comments")
		(21 "Eco1.User" user "User.Eco1")
		(23 "Eco2.User" user "User.Eco2")
		(25 "Edge.Cuts" user "Board Geometry/Outline")
		(27 "Margin" user)
		(31 "F.CrtYd" user "Package Geometry/Place Bound Top")
		(29 "B.CrtYd" user "Package Geometry/Place Bound Bottom")
		(35 "F.Fab" user "Ref Des/Assembly Top")
		(33 "B.Fab" user "Ref Des/Assembly Bottom")
	)
	(footprint ""
		(layer "F.Cu")
		(at 13.335 -166.116 180)
		(property "Reference" "R5509"
			(at 0 0 180)
			(layer "F.SilkS")
			(hide yes)
			(effects
				(font
					(size 1.27 1.27)
				)
			)
		)
		(property "Value" ""
			(at 0 0 180)
			(layer "F.Fab")
			(effects
				(font
					(size 1.27 1.27)
				)
			)
		)
		(duplicate_pad_numbers_are_jumpers no)
		(fp_line
			(start 0.7874 0.4064)
			(end -0.7874 0.4064)
			(stroke
				(width 0.1524)
				(type default)
			)
			(layer "F.SilkS")
		)
		(fp_line
			(start 0.7874 -0.4064)
			(end 0.7874 0.4064)
			(stroke
				(width 0.1524)
				(type default)
			)
			(layer "F.SilkS")
		)
		(fp_line
			(start -0.7874 0.4064)
			(end -0.7874 -0.4064)
			(stroke
				(width 0.1524)
				(type default)
			)
			(layer "F.SilkS")
		)
		(fp_line
			(start -0.7874 -0.4064)
			(end 0.7874 -0.4064)
			(stroke
				(width 0.1524)
				(type default)
			)
			(layer "F.SilkS")
		)
		(fp_line
			(start 0.67945 0.3048)
			(end 0.120396 0.3048)
			(stroke
				(width 0.1)
				(type default)
			)
			(layer "F.Fab")
		)
		(fp_line
			(start 0.67945 -0.3048)
			(end 0.67945 0.3048)
			(stroke
				(width 0.1)
				(type default)
			)
			(layer "F.Fab")
		)
		(fp_line
			(start 0.12065 -0.2794)
			(end 0.12065 -0.3048)
			(stroke
				(width 0.1)
				(type default)
			)
			(layer "F.Fab")
		)
		(fp_line
			(start 0.12065 -0.3048)
			(end 0.67945 -0.3048)
			(stroke
				(width 0.1)
				(type default)
			)
			(layer "F.Fab")
		)
		(fp_line
			(start 0.120396 0.3048)
			(end 0.120396 0.2794)
			(stroke
				(width 0.1)
				(type default)
			)
			(layer "F.Fab")
		)
		(fp_line
			(start 0.120396 0.2794)
			(end -0.12065 0.2794)
			(stroke
				(width 0.1)
				(type default)
			)
			(layer "F.Fab")
		)
		(fp_line
			(start -0.12065 0.3048)
			(end -0.67945 0.3048)
			(stroke
				(width 0.1)
				(type default)
			)
			(layer "F.Fab")
		)
		(fp_line
			(start -0.12065 0.2794)
			(end -0.12065 0.3048)
			(stroke
				(width 0.1)
				(type default)
			)
			(layer "F.Fab")
		)
		(fp_line
			(start -0.12065 -0.2794)
			(end 0.12065 -0.2794)
			(stroke
				(width 0.1)
				(type default)
			)
			(layer "F.Fab")
		)
		(fp_line
			(start -0.12065 -0.305054)
			(end -0.12065 -0.2794)
			(stroke
				(width 0.1)
				(type default)
			)
			(layer "F.Fab")
		)
		(fp_line
			(start -0.67945 0.3048)
			(end -0.67945 -0.305054)
			(stroke
				(width 0.1)
				(type default)
			)
			(layer "F.Fab")
		)
		(fp_line
			(start -0.67945 -0.305054)
			(end -0.12065 -0.305054)
			(stroke
				(width 0.1)
				(type default)
			)
			(layer "F.Fab")
		)
		(pad "1" smd circle
			(at -0.40005 0 180)
			(size 0 0)
			(layers "F.Cu" "F.Mask" "F.Paste")
			(net "P3V3_AUX")
		)
		(pad "2" smd circle
			(at 0.40005 0 180)
			(size 0 0)
			(layers "F.Cu" "F.Mask" "F.Paste")
			(net "FAN_2_PRESENT_N")
		)
	)
	(footprint ""
		(layer "F.Cu")
		(at 18.679922 -14.310868 180)
		(property "Reference" "D243"
			(at 0.772922 -1.383538 0)
			(unlocked yes)
			(layer "F.SilkS")
			(effects
				(font
					(size 0.7874 0.5842)
					(thickness 0.1524)
				)
				(justify left)
			)
		)
		(property "Value" ""
			(at 0 0 180)
			(layer "F.Fab")
			(effects
				(font
					(size 1.27 1.27)
				)
			)
		)
		(duplicate_pad_numbers_are_jumpers no)
		(fp_line
			(start 0.94488 0.450088)
			(end 0.94488 -0.450088)
			(stroke
				(width 0.1524)
				(type default)
			)
			(layer "F.SilkS")
		)
		(fp_line
			(start 0.94488 -0.450088)
			(end -0.854964 -0.450088)
			(stroke
				(width 0.1524)
				(type default)
			)
			(layer "F.SilkS")
		)
		(fp_line
			(start 0.870458 -0.2794)
			(end 0.845058 0.4064)
			(stroke
				(width 0.1524)
				(type default)
			)
			(layer "F.SilkS")
		)
		(fp_line
			(start 0.845058 0.4064)
			(end 0.845058 -0.381)
			(stroke
				(width 0.1524)
				(type default)
			)
			(layer "F.SilkS")
		)
		(fp_line
			(start -0.854964 0.450088)
			(end 0.925068 0.450088)
			(stroke
				(width 0.1524)
				(type default)
			)
			(layer "F.SilkS")
		)
		(fp_line
			(start -0.854964 -0.450088)
			(end -0.854964 0.450088)
			(stroke
				(width 0.1524)
				(type default)
			)
			(layer "F.SilkS")
		)
		(fp_line
			(start 0.54991 0.350012)
			(end 0.54991 -0.350012)
			(stroke
				(width 0.1)
				(type default)
			)
			(layer "F.Fab")
		)
		(fp_line
			(start 0.54991 -0.350012)
			(end -0.54991 -0.350012)
			(stroke
				(width 0.1)
				(type default)
			)
			(layer "F.Fab")
		)
		(fp_line
			(start -0.54991 0.350012)
			(end 0.54991 0.350012)
			(stroke
				(width 0.1)
				(type default)
			)
			(layer "F.Fab")
		)
		(fp_line
			(start -0.54991 -0.350012)
			(end -0.54991 0.350012)
			(stroke
				(width 0.1)
				(type default)
			)
			(layer "F.Fab")
		)
		(fp_text user "-"
			(at 1.915922 -0.499618 0)
			(unlocked yes)
			(layer "F.SilkS")
			(effects
				(font
					(size 1.905 1.4224)
					(thickness 0.1524)
				)
				(justify left)
			)
		)
		(fp_text user "+"
			(at -0.624078 0.262382 0)
			(unlocked yes)
			(layer "F.SilkS")
			(effects
				(font
					(size 1.905 1.4224)
					(thickness 0.1524)
				)
				(justify left)
			)
		)
		(fp_text user "-"
			(at 2.48539 0.239014 0)
			(unlocked yes)
			(layer "F.Fab")
			(effects
				(font
					(size 1.905 1.4224)
					(thickness 0.1524)
				)
				(justify left)
			)
		)
		(fp_text user "+"
			(at -0.808228 0.239014 0)
			(unlocked yes)
			(layer "F.Fab")
			(effects
				(font
					(size 1.905 1.4224)
					(thickness 0.1524)
				)
				(justify left)
			)
		)
		(pad "A" smd rect
			(at -0.424942 0 180)
			(size 0.5588 0.6096)
			(layers "F.Cu" "F.Mask" "F.Paste")
			(net "GND")
		)
		(pad "C" smd rect
			(at 0.424942 0)
			(size 0.5588 0.6096)
			(layers "F.Cu" "F.Mask" "F.Paste")
			(net "FAN_4_PWM_OL_R")
		)
	)
	(footprint ""
		(layer "F.Cu")
		(at 36.068 -250.444 -90)
		(property "Reference" "PR28"
			(at 0 0 270)
			(layer "F.SilkS")
			(hide yes)
			(effects
				(font
					(size 1.27 1.27)
				)
			)
		)
		(property "Value" ""
			(at 0 0 270)
			(layer "F.Fab")
			(effects
				(font
					(size 1.27 1.27)
				)
			)
		)
		(duplicate_pad_numbers_are_jumpers no)
		(fp_line
			(start -0.7874 0.4064)
			(end -0.7874 -0.4064)
			(stroke
				(width 0.1524)
				(type default)
			)
			(layer "F.SilkS")
		)
		(fp_line
			(start 0.7874 0.4064)
			(end -0.7874 0.4064)
			(stroke
				(width 0.1524)
				(type default)
			)
			(layer "F.SilkS")
		)
		(fp_line
			(start -0.7874 -0.4064)
			(end 0.7874 -0.4064)
			(stroke
				(width 0.1524)
				(type default)
			)
			(layer "F.SilkS")
		)
		(fp_line
			(start 0.7874 -0.4064)
			(end 0.7874 0.4064)
			(stroke
				(width 0.1524)
				(type default)
			)
			(layer "F.SilkS")
		)
		(fp_line
			(start -0.67945 0.3048)
			(end -0.67945 -0.305054)
			(stroke
				(width 0.1)
				(type default)
			)
			(layer "F.Fab")
		)
		(fp_line
			(start -0.12065 0.3048)
			(end -0.67945 0.3048)
			(stroke
				(width 0.1)
				(type default)
			)
			(layer "F.Fab")
		)
		(fp_line
			(start 0.120396 0.3048)
			(end 0.120396 0.2794)
			(stroke
				(width 0.1)
				(type default)
			)
			(layer "F.Fab")
		)
		(fp_line
			(start 0.67945 0.3048)
			(end 0.120396 0.3048)
			(stroke
				(width 0.1)
				(type default)
			)
			(layer "F.Fab")
		)
		(fp_line
			(start -0.12065 0.2794)
			(end -0.12065 0.3048)
			(stroke
				(width 0.1)
				(type default)
			)
			(layer "F.Fab")
		)
		(fp_line
			(start 0.120396 0.2794)
			(end -0.12065 0.2794)
			(stroke
				(width 0.1)
				(type default)
			)
			(layer "F.Fab")
		)
		(fp_line
			(start -0.12065 -0.2794)
			(end 0.12065 -0.2794)
			(stroke
				(width 0.1)
				(type default)
			)
			(layer "F.Fab")
		)
		(fp_line
			(start 0.12065 -0.2794)
			(end 0.12065 -0.3048)
			(stroke
				(width 0.1)
				(type default)
			)
			(layer "F.Fab")
		)
		(fp_line
			(start 0.12065 -0.3048)
			(end 0.67945 -0.3048)
			(stroke
				(width 0.1)
				(type default)
			)
			(layer "F.Fab")
		)
		(fp_line
			(start 0.67945 -0.3048)
			(end 0.67945 0.3048)
			(stroke
				(width 0.1)
				(type default)
			)
			(layer "F.Fab")
		)
		(fp_line
			(start -0.67945 -0.305054)
			(end -0.12065 -0.305054)
			(stroke
				(width 0.1)
				(type default)
			)
			(layer "F.Fab")
		)
		(fp_line
			(start -0.12065 -0.305054)
			(end -0.12065 -0.2794)
			(stroke
				(width 0.1)
				(type default)
			)
			(layer "F.Fab")
		)
		(pad "1" smd rect
			(at -0.40005 0 90)
			(size 0.4572 0.508)
			(layers "F.Cu" "F.Mask" "F.Paste")
			(net "FAN_1_FAULT_R")
		)
		(pad "2" smd rect
			(at 0.40005 0 90)
			(size 0.4572 0.508)
			(layers "F.Cu" "F.Mask" "F.Paste")
			(net "FAN_1_FAULT")
		)
	)
	(footprint ""
		(layer "F.Cu")
		(at 20.828 -170.688)
		(property "Reference" "R5673"
			(at 0 0 0)
			(layer "F.SilkS")
			(hide yes)
			(effects
				(font
					(size 1.27 1.27)
				)
			)
		)
		(property "Value" ""
			(at 0 0 0)
			(layer "F.Fab")
			(effects
				(font
					(size 1.27 1.27)
				)
			)
		)
		(duplicate_pad_numbers_are_jumpers no)
		(fp_line
			(start -0.7874 -0.4064)
			(end 0.7874 -0.4064)
			(stroke
				(width 0.1524)
				(type default)
			)
			(layer "F.SilkS")
		)
		(fp_line
			(start -0.7874 0.4064)
			(end -0.7874 -0.4064)
			(stroke
				(width 0.1524)
				(type default)
			)
			(layer "F.SilkS")
		)
		(fp_line
			(start 0.7874 -0.4064)
			(end 0.7874 0.4064)
			(stroke
				(width 0.1524)
				(type default)
			)
			(layer "F.SilkS")
		)
		(fp_line
			(start 0.7874 0.4064)
			(end -0.7874 0.4064)
			(stroke
				(width 0.1524)
				(type default)
			)
			(layer "F.SilkS")
		)
		(fp_line
			(start -0.67945 -0.305054)
			(end -0.12065 -0.305054)
			(stroke
				(width 0.1)
				(type default)
			)
			(layer "F.Fab")
		)
		(fp_line
			(start -0.67945 0.3048)
			(end -0.67945 -0.305054)
			(stroke
				(width 0.1)
				(type default)
			)
			(layer "F.Fab")
		)
		(fp_line
			(start -0.12065 -0.305054)
			(end -0.12065 -0.2794)
			(stroke
				(width 0.1)
				(type default)
			)
			(layer "F.Fab")
		)
		(fp_line
			(start -0.12065 -0.2794)
			(end 0.12065 -0.2794)
			(stroke
				(width 0.1)
				(type default)
			)
			(layer "F.Fab")
		)
		(fp_line
			(start -0.12065 0.2794)
			(end -0.12065 0.3048)
			(stroke
				(width 0.1)
				(type default)
			)
			(layer "F.Fab")
		)
		(fp_line
			(start -0.12065 0.3048)
			(end -0.67945 0.3048)
			(stroke
				(width 0.1)
				(type default)
			)
			(layer "F.Fab")
		)
		(fp_line
			(start 0.120396 0.2794)
			(end -0.12065 0.2794)
			(stroke
				(width 0.1)
				(type default)
			)
			(layer "F.Fab")
		)
		(fp_line
			(start 0.120396 0.3048)
			(end 0.120396 0.2794)
			(stroke
				(width 0.1)
				(type default)
			)
			(layer "F.Fab")
		)
		(fp_line
			(start 0.12065 -0.3048)
			(end 0.67945 -0.3048)
			(stroke
				(width 0.1)
				(type default)
			)
			(layer "F.Fab")
		)
		(fp_line
			(start 0.12065 -0.2794)
			(end 0.12065 -0.3048)
			(stroke
				(width 0.1)
				(type default)
			)
			(layer "F.Fab")
		)
		(fp_line
			(start 0.67945 -0.3048)
			(end 0.67945 0.3048)
			(stroke
				(width 0.1)
				(type default)
			)
			(layer "F.Fab")
		)
		(fp_line
			(start 0.67945 0.3048)
			(end 0.120396 0.3048)
			(stroke
				(width 0.1)
				(type default)
			)
			(layer "F.Fab")
		)
		(pad "1" smd circle
			(at -0.40005 0)
			(size 0 0)
			(layers "F.Cu" "F.Mask" "F.Paste")
			(net "FM_BOARD_SKU_ID0")
		)
		(pad "2" smd circle
			(at 0.40005 0)
			(size 0 0)
			(layers "F.Cu" "F.Mask" "F.Paste")
			(net "GND")
		)
	)
	(footprint ""
		(layer "F.Cu")
		(at 32.893 -304.292)
		(property "Reference" "D267"
			(at -0.9906 -1.48463 0)
			(unlocked yes)
			(layer "F.SilkS")
			(effects
				(font
					(size 0.7874 0.5842)
					(thickness 0.1524)
				)
				(justify left)
			)
		)
		(property "Value" ""
			(at 0 0 0)
			(layer "F.Fab")
			(effects
				(font
					(size 1.27 1.27)
				)
			)
		)
		(duplicate_pad_numbers_are_jumpers no)
		(fp_line
			(start -0.854964 -0.450088)
			(end -0.854964 0.450088)
			(stroke
				(width 0.1524)
				(type default)
			)
			(layer "F.SilkS")
		)
		(fp_line
			(start -0.854964 0.450088)
			(end 0.925068 0.450088)
			(stroke
				(width 0.1524)
				(type default)
			)
			(layer "F.SilkS")
		)
		(fp_line
			(start 0.845058 0.4064)
			(end 0.845058 -0.381)
			(stroke
				(width 0.1524)
				(type default)
			)
			(layer "F.SilkS")
		)
		(fp_line
			(start 0.870458 -0.2794)
			(end 0.845058 0.4064)
			(stroke
				(width 0.1524)
				(type default)
			)
			(layer "F.SilkS")
		)
		(fp_line
			(start 0.94488 -0.450088)
			(end -0.854964 -0.450088)
			(stroke
				(width 0.1524)
				(type default)
			)
			(layer "F.SilkS")
		)
		(fp_line
			(start 0.94488 0.450088)
			(end 0.94488 -0.450088)
			(stroke
				(width 0.1524)
				(type default)
			)
			(layer "F.SilkS")
		)
		(fp_line
			(start -0.54991 -0.350012)
			(end -0.54991 0.350012)
			(stroke
				(width 0.1)
				(type default)
			)
			(layer "F.Fab")
		)
		(fp_line
			(start -0.54991 0.350012)
			(end 0.54991 0.350012)
			(stroke
				(width 0.1)
				(type default)
			)
			(layer "F.Fab")
		)
		(fp_line
			(start 0.54991 -0.350012)
			(end -0.54991 -0.350012)
			(stroke
				(width 0.1)
				(type default)
			)
			(layer "F.Fab")
		)
		(fp_line
			(start 0.54991 0.350012)
			(end 0.54991 -0.350012)
			(stroke
				(width 0.1)
				(type default)
			)
			(layer "F.Fab")
		)
		(fp_text user "+"
			(at -0.808228 0.239014 180)
			(unlocked yes)
			(layer "F.SilkS")
			(effects
				(font
					(size 1.905 1.4224)
					(thickness 0.1524)
				)
				(justify left)
			)
		)
		(fp_text user "-"
			(at 1.9558 -0.48895 180)
			(unlocked yes)
			(layer "F.SilkS")
			(effects
				(font
					(size 1.905 1.4224)
					(thickness 0.1524)
				)
				(justify left)
			)
		)
		(fp_text user "+"
			(at -0.808228 0.239014 180)
			(unlocked yes)
			(layer "F.Fab")
			(effects
				(font
					(size 1.905 1.4224)
					(thickness 0.1524)
				)
				(justify left)
			)
		)
		(fp_text user "-"
			(at 2.48539 0.239014 180)
			(unlocked yes)
			(layer "F.Fab")
			(effects
				(font
					(size 1.905 1.4224)
					(thickness 0.1524)
				)
				(justify left)
			)
		)
		(pad "A" smd rect
			(at -0.424942 0)
			(size 0.5588 0.6096)
			(layers "F.Cu" "F.Mask" "F.Paste")
			(net "GND")
		)
		(pad "C" smd rect
			(at 0.424942 0 180)
			(size 0.5588 0.6096)
			(layers "F.Cu" "F.Mask" "F.Paste")
			(net "FAN_0_PWM_OL_R")
		)
	)
	(footprint ""
		(layer "F.Cu")
		(at 25.850088 -326.909938)
		(property "Reference" "H11"
			(at -1.085088 -5.713222 0)
			(unlocked yes)
			(layer "F.SilkS")
			(effects
				(font
					(size 0.7874 0.5842)
					(thickness 0.1524)
				)
				(justify left)
			)
		)
		(property "Value" ""
			(at 0 0 0)
			(layer "F.Fab")
			(effects
				(font
					(size 1.27 1.27)
				)
			)
		)
		(duplicate_pad_numbers_are_jumpers no)
		(pad "1" thru_hole circle
			(at 0 0)
			(size 10.16 10.16)
			(drill 6.4008
				(offset 0 0)
			)
			(layers "*.Cu" "*.Mask")
			(remove_unused_layers no)
			(net "GND")
			(clearance -1.6256)
			(padstack
				(mode front_inner_back)
				(layer "Inner"
					(shape circle)
					(size 10.16 10.16)
					(clearance -1.6256)
				)
				(layer "B.Cu"
					(shape oval)
					(size 10.0076 32.004)
					(offset 0 10.9982)
					(clearance -1.5494)
				)
			)
		)
	)
	(footprint ""
		(layer "F.Cu")
		(at 27.432 -185.674 180)
		(property "Reference" "R5493"
			(at 0 0 180)
			(layer "F.SilkS")
			(hide yes)
			(effects
				(font
					(size 1.27 1.27)
				)
			)
		)
		(property "Value" ""
			(at 0 0 180)
			(layer "F.Fab")
			(effects
				(font
					(size 1.27 1.27)
				)
			)
		)
		(duplicate_pad_numbers_are_jumpers no)
		(fp_line
			(start 0.7874 0.4064)
			(end -0.7874 0.4064)
			(stroke
				(width 0.1524)
				(type default)
			)
			(layer "F.SilkS")
		)
		(fp_line
			(start 0.7874 -0.4064)
			(end 0.7874 0.4064)
			(stroke
				(width 0.1524)
				(type default)
			)
			(layer "F.SilkS")
		)
		(fp_line
			(start -0.7874 0.4064)
			(end -0.7874 -0.4064)
			(stroke
				(width 0.1524)
				(type default)
			)
			(layer "F.SilkS")
		)
		(fp_line
			(start -0.7874 -0.4064)
			(end 0.7874 -0.4064)
			(stroke
				(width 0.1524)
				(type default)
			)
			(layer "F.SilkS")
		)
		(fp_line
			(start 0.67945 0.3048)
			(end 0.120396 0.3048)
			(stroke
				(width 0.1)
				(type default)
			)
			(layer "F.Fab")
		)
		(fp_line
			(start 0.67945 -0.3048)
			(end 0.67945 0.3048)
			(stroke
				(width 0.1)
				(type default)
			)
			(layer "F.Fab")
		)
		(fp_line
			(start 0.12065 -0.2794)
			(end 0.12065 -0.3048)
			(stroke
				(width 0.1)
				(type default)
			)
			(layer "F.Fab")
		)
		(fp_line
			(start 0.12065 -0.3048)
			(end 0.67945 -0.3048)
			(stroke
				(width 0.1)
				(type default)
			)
			(layer "F.Fab")
		)
		(fp_line
			(start 0.120396 0.3048)
			(end 0.120396 0.2794)
			(stroke
				(width 0.1)
				(type default)
			)
			(layer "F.Fab")
		)
		(fp_line
			(start 0.120396 0.2794)
			(end -0.12065 0.2794)
			(stroke
				(width 0.1)
				(type default)
			)
			(layer "F.Fab")
		)
		(fp_line
			(start -0.12065 0.3048)
			(end -0.67945 0.3048)
			(stroke
				(width 0.1)
				(type default)
			)
			(layer "F.Fab")
		)
		(fp_line
			(start -0.12065 0.2794)
			(end -0.12065 0.3048)
			(stroke
				(width 0.1)
				(type default)
			)
			(layer "F.Fab")
		)
		(fp_line
			(start -0.12065 -0.2794)
			(end 0.12065 -0.2794)
			(stroke
				(width 0.1)
				(type default)
			)
			(layer "F.Fab")
		)
		(fp_line
			(start -0.12065 -0.305054)
			(end -0.12065 -0.2794)
			(stroke
				(width 0.1)
				(type default)
			)
			(layer "F.Fab")
		)
		(fp_line
			(start -0.67945 0.3048)
			(end -0.67945 -0.305054)
			(stroke
				(width 0.1)
				(type default)
			)
			(layer "F.Fab")
		)
		(fp_line
			(start -0.67945 -0.305054)
			(end -0.12065 -0.305054)
			(stroke
				(width 0.1)
				(type default)
			)
			(layer "F.Fab")
		)
		(pad "1" smd circle
			(at -0.40005 0 180)
			(size 0 0)
			(layers "F.Cu" "F.Mask" "F.Paste")
			(net "P52V_FAN_6_BUFF_EN")
		)
		(pad "2" smd circle
			(at 0.40005 0 180)
			(size 0 0)
			(layers "F.Cu" "F.Mask" "F.Paste")
			(net "P52V_FAN_6_BUFF_EN_R")
		)
	)
)
